# T6G (Grand Teton) — schematic netlist excerpt (pin names and nets, part order shuffled) for the footprints in the layout excerpt that follows; sources: Cadence DE-HDL packaged netlist, KiCad conversion of 04192023_DAF0TMB3IC0_F0TG_MB_C_brd_V02_OCP.brd

R1506  Q_RES  30K 1% CHIP  pkg 0402LF  page 29 : A = PVDD18_S5_P0 ; B = ESPI_CPU0_D3
C3903  Q_CAP  22UF 4V 20% X6S  pkg C0402  page 72 : A = PVDD11_S3_P1 ; B = GND

(kicad_pcb
	(version 20260206)
	(generator "pcbnew")
	(generator_version "10.0")
	(general
		(thickness 1.6)
		(legacy_teardrops no)
	)
	(paper "A4")
	(title_block
		(title "04192023_DAF0TMB3IC0_F0TG_MB_C_brd_V02_OCP.brd")
		(comment 1 "Grand Teton / footprints 5312-5313 of 8354")
	)
	(layers
		(0 "F.Cu" signal "TOP")
		(4 "In1.Cu" signal "GND")
		(6 "In2.Cu" signal "IN1")
		(8 "In3.Cu" signal "GND1")
		(10 "In4.Cu" signal "IN2")
		(12 "In5.Cu" signal "GND2")
		(14 "In6.Cu" signal "IN3")
		(16 "In7.Cu" signal "GND3")
		(18 "In8.Cu" signal "VCC")
		(20 "In9.Cu" signal "VCC1")
		(22 "In10.Cu" signal "GND4")
		(24 "In11.Cu" signal "IN4")
		(26 "In12.Cu" signal "GND5")
		(28 "In13.Cu" signal "IN5")
		(30 "In14.Cu" signal "GND6")
		(32 "In15.Cu" signal "IN6")
		(34 "In16.Cu" signal "GND7")
		(2 "B.Cu" signal "BOTTOM")
		(9 "F.Adhes" user "F.Adhesive")
		(11 "B.Adhes" user "B.Adhesive")
		(13 "F.Paste" user "Package Geometry/Pastemask Top")
		(15 "B.Paste" user "Package Geometry/Pastemask Bottom")
		(5 "F.SilkS" user "Ref Des/Silkscreen Top")
		(7 "B.SilkS" user "Ref Des/Silkscreen Bottom")
		(1 "F.Mask" user "Board Geometry/Soldermask Top")
		(3 "B.Mask" user "Board Geometry/Soldermask Bottom")
		(17 "Dwgs.User" user "User.Drawings")
		(19 "Cmts.User" user "User.Comments")
		(21 "Eco1.User" user "User.Eco1")
		(23 "Eco2.User" user "User.Eco2")
		(25 "Edge.Cuts" user "Board Geometry/Outline")
		(27 "Margin" user)
		(31 "F.CrtYd" user "Package Geometry/Place Bound Top")
		(29 "B.CrtYd" user "Package Geometry/Place Bound Bottom")
		(35 "F.Fab" user "Ref Des/Assembly Top")
		(33 "B.Fab" user "Ref Des/Assembly Bottom")
	)
	(footprint ""
		(layer "B.Cu")
		(at 396.792958 -326.163432)
		(property "Reference" "R1506"
			(at 0 0 0)
			(layer "B.SilkS")
			(hide yes)
			(effects
				(font
					(size 1.27 1.27)
				)
				(justify mirror)
			)
		)
		(property "Value" ""
			(at 0 0 0)
			(layer "B.Fab")
			(effects
				(font
					(size 1.27 1.27)
				)
				(justify mirror)
			)
		)
		(duplicate_pad_numbers_are_jumpers no)
		(fp_line
			(start -0.7874 -0.4064)
			(end -0.7874 0.4064)
			(stroke
				(width 0.1524)
				(type default)
			)
			(layer "B.SilkS")
		)
		(fp_line
			(start -0.7874 0.4064)
			(end 0.7874 0.4064)
			(stroke
				(width 0.1524)
				(type default)
			)
			(layer "B.SilkS")
		)
		(fp_line
			(start 0.7874 -0.4064)
			(end -0.7874 -0.4064)
			(stroke
				(width 0.1524)
				(type default)
			)
			(layer "B.SilkS")
		)
		(fp_line
			(start 0.7874 0.4064)
			(end 0.7874 -0.4064)
			(stroke
				(width 0.1524)
				(type default)
			)
			(layer "B.SilkS")
		)
		(fp_line
			(start -0.67945 -0.3048)
			(end -0.67945 0.3048)
			(stroke
				(width 0.1)
				(type default)
			)
			(layer "B.Fab")
		)
		(fp_line
			(start -0.67945 0.3048)
			(end -0.120396 0.3048)
			(stroke
				(width 0.1)
				(type default)
			)
			(layer "B.Fab")
		)
		(fp_line
			(start -0.12065 -0.3048)
			(end -0.67945 -0.3048)
			(stroke
				(width 0.1)
				(type default)
			)
			(layer "B.Fab")
		)
		(fp_line
			(start -0.12065 -0.2794)
			(end -0.12065 -0.3048)
			(stroke
				(width 0.1)
				(type default)
			)
			(layer "B.Fab")
		)
		(fp_line
			(start -0.120396 0.2794)
			(end 0.12065 0.2794)
			(stroke
				(width 0.1)
				(type default)
			)
			(layer "B.Fab")
		)
		(fp_line
			(start -0.120396 0.3048)
			(end -0.120396 0.2794)
			(stroke
				(width 0.1)
				(type default)
			)
			(layer "B.Fab")
		)
		(fp_line
			(start 0.12065 -0.305054)
			(end 0.12065 -0.2794)
			(stroke
				(width 0.1)
				(type default)
			)
			(layer "B.Fab")
		)
		(fp_line
			(start 0.12065 -0.2794)
			(end -0.12065 -0.2794)
			(stroke
				(width 0.1)
				(type default)
			)
			(layer "B.Fab")
		)
		(fp_line
			(start 0.12065 0.2794)
			(end 0.12065 0.3048)
			(stroke
				(width 0.1)
				(type default)
			)
			(layer "B.Fab")
		)
		(fp_line
			(start 0.12065 0.3048)
			(end 0.67945 0.3048)
			(stroke
				(width 0.1)
				(type default)
			)
			(layer "B.Fab")
		)
		(fp_line
			(start 0.67945 -0.305054)
			(end 0.12065 -0.305054)
			(stroke
				(width 0.1)
				(type default)
			)
			(layer "B.Fab")
		)
		(fp_line
			(start 0.67945 0.3048)
			(end 0.67945 -0.305054)
			(stroke
				(width 0.1)
				(type default)
			)
			(layer "B.Fab")
		)
		(pad "1" smd circle
			(at 0.40005 0 180)
			(size 0 0)
			(layers "B.Cu" "B.Mask" "B.Paste")
			(net "PVDD18_S5_P0")
		)
		(pad "2" smd circle
			(at -0.40005 0 180)
			(size 0 0)
			(layers "B.Cu" "B.Mask" "B.Paste")
			(net "ESPI_CPU0_D3")
		)
	)
	(footprint ""
		(layer "B.Cu")
		(at 106.466386 -264.354564)
		(property "Reference" "C3903"
			(at 0 0 0)
			(layer "B.SilkS")
			(hide yes)
			(effects
				(font
					(size 1.27 1.27)
				)
				(justify mirror)
			)
		)
		(property "Value" ""
			(at 0 0 0)
			(layer "B.Fab")
			(effects
				(font
					(size 1.27 1.27)
				)
				(justify mirror)
			)
		)
		(duplicate_pad_numbers_are_jumpers no)
		(fp_line
			(start -0.7874 -0.4064)
			(end -0.7874 0.4064)
			(stroke
				(width 0.1524)
				(type default)
			)
			(layer "B.SilkS")
		)
		(fp_line
			(start -0.7874 0.4064)
			(end 0.7874 0.4064)
			(stroke
				(width 0.1524)
				(type default)
			)
			(layer "B.SilkS")
		)
		(fp_line
			(start 0.7874 -0.4064)
			(end -0.7874 -0.4064)
			(stroke
				(width 0.1524)
				(type default)
			)
			(layer "B.SilkS")
		)
		(fp_line
			(start 0.7874 0.4064)
			(end 0.7874 -0.4064)
			(stroke
				(width 0.1524)
				(type default)
			)
			(layer "B.SilkS")
		)
		(fp_line
			(start -0.67945 -0.3048)
			(end -0.67945 0.3048)
			(stroke
				(width 0.1)
				(type default)
			)
			(layer "B.Fab")
		)
		(fp_line
			(start -0.67945 0.3048)
			(end -0.120396 0.3048)
			(stroke
				(width 0.1)
				(type default)
			)
			(layer "B.Fab")
		)
		(fp_line
			(start -0.12065 -0.3048)
			(end -0.67945 -0.3048)
			(stroke
				(width 0.1)
				(type default)
			)
			(layer "B.Fab")
		)
		(fp_line
			(start -0.12065 -0.2794)
			(end -0.12065 -0.3048)
			(stroke
				(width 0.1)
				(type default)
			)
			(layer "B.Fab")
		)
		(fp_line
			(start -0.120396 0.2794)
			(end 0.12065 0.2794)
			(stroke
				(width 0.1)
				(type default)
			)
			(layer "B.Fab")
		)
		(fp_line
			(start -0.120396 0.3048)
			(end -0.120396 0.2794)
			(stroke
				(width 0.1)
				(type default)
			)
			(layer "B.Fab")
		)
		(fp_line
			(start 0.12065 -0.305054)
			(end 0.12065 -0.2794)
			(stroke
				(width 0.1)
				(type default)
			)
			(layer "B.Fab")
		)
		(fp_line
			(start 0.12065 -0.2794)
			(end -0.12065 -0.2794)
			(stroke
				(width 0.1)
				(type default)
			)
			(layer "B.Fab")
		)
		(fp_line
			(start 0.12065 0.2794)
			(end 0.12065 0.3048)
			(stroke
				(width 0.1)
				(type default)
			)
			(layer "B.Fab")
		)
		(fp_line
			(start 0.12065 0.3048)
			(end 0.67945 0.3048)
			(stroke
				(width 0.1)
				(type default)
			)
			(layer "B.Fab")
		)
		(fp_line
			(start 0.67945 -0.305054)
			(end 0.12065 -0.305054)
			(stroke
				(width 0.1)
				(type default)
			)
			(layer "B.Fab")
		)
		(fp_line
			(start 0.67945 0.3048)
			(end 0.67945 -0.305054)
			(stroke
				(width 0.1)
				(type default)
			)
			(layer "B.Fab")
		)
		(pad "1" smd circle
			(at 0.40005 0 180)
			(size 0 0)
			(layers "B.Cu" "B.Mask" "B.Paste")
			(net "PVDD11_S3_P1")
		)
		(pad "2" smd circle
			(at -0.40005 0 180)
			(size 0 0)
			(layers "B.Cu" "B.Mask" "B.Paste")
			(net "GND")
		)
	)
)
